# T6G (Grand Teton) — schematic netlist excerpt (pin names and nets, part order shuffled) for the footprints in the layout excerpt that follows; sources: Cadence DE-HDL packaged netlist, KiCad conversion of 04192023_DAF0TMB3IC0_F0TG_MB_C_brd_V02_OCP.brd

PR280  Q_RES  0 5% CHIP  pkg 0402LF  page 222 : A = PVDDIO_P1_VOS1 ; B = PVDDIO_P1
R1711  Q_RES  10 1% CHIP  pkg 0402LF  page 109 : A = I3C_SPD_DDRGL_CPU1_SDA ; B = I3C_SPD_DDRL_CPU1_SDA
R841  Q_RES  1K 1% CHIP  pkg 0201LF  page 185 : A = P1V8_CPU0_RT_1D ; B = SMB_RT_CPU0_P2_ROM_R_SCL

(kicad_pcb
	(version 20260206)
	(generator "pcbnew")
	(generator_version "10.0")
	(general
		(thickness 1.6)
		(legacy_teardrops no)
	)
	(paper "A4")
	(title_block
		(title "04192023_DAF0TMB3IC0_F0TG_MB_C_brd_V02_OCP.brd")
		(comment 1 "Grand Teton / footprints 8068-8070 of 8354")
	)
	(layers
		(0 "F.Cu" signal "TOP")
		(4 "In1.Cu" signal "GND")
		(6 "In2.Cu" signal "IN1")
		(8 "In3.Cu" signal "GND1")
		(10 "In4.Cu" signal "IN2")
		(12 "In5.Cu" signal "GND2")
		(14 "In6.Cu" signal "IN3")
		(16 "In7.Cu" signal "GND3")
		(18 "In8.Cu" signal "VCC")
		(20 "In9.Cu" signal "VCC1")
		(22 "In10.Cu" signal "GND4")
		(24 "In11.Cu" signal "IN4")
		(26 "In12.Cu" signal "GND5")
		(28 "In13.Cu" signal "IN5")
		(30 "In14.Cu" signal "GND6")
		(32 "In15.Cu" signal "IN6")
		(34 "In16.Cu" signal "GND7")
		(2 "B.Cu" signal "BOTTOM")
		(9 "F.Adhes" user "F.Adhesive")
		(11 "B.Adhes" user "B.Adhesive")
		(13 "F.Paste" user "Package Geometry/Pastemask Top")
		(15 "B.Paste" user "Package Geometry/Pastemask Bottom")
		(5 "F.SilkS" user "Ref Des/Silkscreen Top")
		(7 "B.SilkS" user "Ref Des/Silkscreen Bottom")
		(1 "F.Mask" user "Board Geometry/Soldermask Top")
		(3 "B.Mask" user "Board Geometry/Soldermask Bottom")
		(17 "Dwgs.User" user "User.Drawings")
		(19 "Cmts.User" user "User.Comments")
		(21 "Eco1.User" user "User.Eco1")
		(23 "Eco2.User" user "User.Eco2")
		(25 "Edge.Cuts" user "Board Geometry/Outline")
		(27 "Margin" user)
		(31 "F.CrtYd" user "Package Geometry/Place Bound Top")
		(29 "B.CrtYd" user "Package Geometry/Place Bound Bottom")
		(35 "F.Fab" user "Ref Des/Assembly Top")
		(33 "B.Fab" user "Ref Des/Assembly Bottom")
	)
	(footprint ""
		(layer "B.Cu")
		(at 206.22133 -195.95211)
		(property "Reference" "R1711"
			(at 0 0 0)
			(layer "B.SilkS")
			(hide yes)
			(effects
				(font
					(size 1.27 1.27)
				)
				(justify mirror)
			)
		)
		(property "Value" ""
			(at 0 0 0)
			(layer "B.Fab")
			(effects
				(font
					(size 1.27 1.27)
				)
				(justify mirror)
			)
		)
		(duplicate_pad_numbers_are_jumpers no)
		(fp_line
			(start -0.7874 -0.4064)
			(end -0.7874 0.4064)
			(stroke
				(width 0.1524)
				(type default)
			)
			(layer "B.SilkS")
		)
		(fp_line
			(start -0.7874 0.4064)
			(end 0.7874 0.4064)
			(stroke
				(width 0.1524)
				(type default)
			)
			(layer "B.SilkS")
		)
		(fp_line
			(start 0.7874 -0.4064)
			(end -0.7874 -0.4064)
			(stroke
				(width 0.1524)
				(type default)
			)
			(layer "B.SilkS")
		)
		(fp_line
			(start 0.7874 0.4064)
			(end 0.7874 -0.4064)
			(stroke
				(width 0.1524)
				(type default)
			)
			(layer "B.SilkS")
		)
		(fp_line
			(start -0.67945 -0.3048)
			(end -0.67945 0.3048)
			(stroke
				(width 0.1)
				(type default)
			)
			(layer "B.Fab")
		)
		(fp_line
			(start -0.67945 0.3048)
			(end -0.120396 0.3048)
			(stroke
				(width 0.1)
				(type default)
			)
			(layer "B.Fab")
		)
		(fp_line
			(start -0.12065 -0.3048)
			(end -0.67945 -0.3048)
			(stroke
				(width 0.1)
				(type default)
			)
			(layer "B.Fab")
		)
		(fp_line
			(start -0.12065 -0.2794)
			(end -0.12065 -0.3048)
			(stroke
				(width 0.1)
				(type default)
			)
			(layer "B.Fab")
		)
		(fp_line
			(start -0.120396 0.2794)
			(end 0.12065 0.2794)
			(stroke
				(width 0.1)
				(type default)
			)
			(layer "B.Fab")
		)
		(fp_line
			(start -0.120396 0.3048)
			(end -0.120396 0.2794)
			(stroke
				(width 0.1)
				(type default)
			)
			(layer "B.Fab")
		)
		(fp_line
			(start 0.12065 -0.305054)
			(end 0.12065 -0.2794)
			(stroke
				(width 0.1)
				(type default)
			)
			(layer "B.Fab")
		)
		(fp_line
			(start 0.12065 -0.2794)
			(end -0.12065 -0.2794)
			(stroke
				(width 0.1)
				(type default)
			)
			(layer "B.Fab")
		)
		(fp_line
			(start 0.12065 0.2794)
			(end 0.12065 0.3048)
			(stroke
				(width 0.1)
				(type default)
			)
			(layer "B.Fab")
		)
		(fp_line
			(start 0.12065 0.3048)
			(end 0.67945 0.3048)
			(stroke
				(width 0.1)
				(type default)
			)
			(layer "B.Fab")
		)
		(fp_line
			(start 0.67945 -0.305054)
			(end 0.12065 -0.305054)
			(stroke
				(width 0.1)
				(type default)
			)
			(layer "B.Fab")
		)
		(fp_line
			(start 0.67945 0.3048)
			(end 0.67945 -0.305054)
			(stroke
				(width 0.1)
				(type default)
			)
			(layer "B.Fab")
		)
		(pad "1" smd circle
			(at 0.40005 0 180)
			(size 0 0)
			(layers "B.Cu" "B.Mask" "B.Paste")
			(net "I3C_SPD_DDRGL_CPU1_SDA")
		)
		(pad "2" smd circle
			(at -0.40005 0 180)
			(size 0 0)
			(layers "B.Cu" "B.Mask" "B.Paste")
			(net "I3C_SPD_DDRL_CPU1_SDA")
		)
	)
	(footprint ""
		(layer "B.Cu")
		(at 49.882044 -349.386398 -90)
		(property "Reference" "PR280"
			(at 0 0 90)
			(layer "B.SilkS")
			(hide yes)
			(effects
				(font
					(size 1.27 1.27)
				)
				(justify mirror)
			)
		)
		(property "Value" ""
			(at 0 0 90)
			(layer "B.Fab")
			(effects
				(font
					(size 1.27 1.27)
				)
				(justify mirror)
			)
		)
		(duplicate_pad_numbers_are_jumpers no)
		(fp_line
			(start -0.7874 0.4064)
			(end 0.7874 0.4064)
			(stroke
				(width 0.1524)
				(type default)
			)
			(layer "B.SilkS")
		)
		(fp_line
			(start 0.7874 0.4064)
			(end 0.7874 -0.4064)
			(stroke
				(width 0.1524)
				(type default)
			)
			(layer "B.SilkS")
		)
		(fp_line
			(start -0.7874 -0.4064)
			(end -0.7874 0.4064)
			(stroke
				(width 0.1524)
				(type default)
			)
			(layer "B.SilkS")
		)
		(fp_line
			(start 0.7874 -0.4064)
			(end -0.7874 -0.4064)
			(stroke
				(width 0.1524)
				(type default)
			)
			(layer "B.SilkS")
		)
		(fp_line
			(start -0.67945 0.3048)
			(end -0.120396 0.3048)
			(stroke
				(width 0.1)
				(type default)
			)
			(layer "B.Fab")
		)
		(fp_line
			(start -0.120396 0.3048)
			(end -0.120396 0.2794)
			(stroke
				(width 0.1)
				(type default)
			)
			(layer "B.Fab")
		)
		(fp_line
			(start 0.12065 0.3048)
			(end 0.67945 0.3048)
			(stroke
				(width 0.1)
				(type default)
			)
			(layer "B.Fab")
		)
		(fp_line
			(start 0.67945 0.3048)
			(end 0.67945 -0.305054)
			(stroke
				(width 0.1)
				(type default)
			)
			(layer "B.Fab")
		)
		(fp_line
			(start -0.120396 0.2794)
			(end 0.12065 0.2794)
			(stroke
				(width 0.1)
				(type default)
			)
			(layer "B.Fab")
		)
		(fp_line
			(start 0.12065 0.2794)
			(end 0.12065 0.3048)
			(stroke
				(width 0.1)
				(type default)
			)
			(layer "B.Fab")
		)
		(fp_line
			(start -0.12065 -0.2794)
			(end -0.12065 -0.3048)
			(stroke
				(width 0.1)
				(type default)
			)
			(layer "B.Fab")
		)
		(fp_line
			(start 0.12065 -0.2794)
			(end -0.12065 -0.2794)
			(stroke
				(width 0.1)
				(type default)
			)
			(layer "B.Fab")
		)
		(fp_line
			(start -0.67945 -0.3048)
			(end -0.67945 0.3048)
			(stroke
				(width 0.1)
				(type default)
			)
			(layer "B.Fab")
		)
		(fp_line
			(start -0.12065 -0.3048)
			(end -0.67945 -0.3048)
			(stroke
				(width 0.1)
				(type default)
			)
			(layer "B.Fab")
		)
		(fp_line
			(start 0.12065 -0.305054)
			(end 0.12065 -0.2794)
			(stroke
				(width 0.1)
				(type default)
			)
			(layer "B.Fab")
		)
		(fp_line
			(start 0.67945 -0.305054)
			(end 0.12065 -0.305054)
			(stroke
				(width 0.1)
				(type default)
			)
			(layer "B.Fab")
		)
		(pad "1" smd circle
			(at 0.40005 0 90)
			(size 0 0)
			(layers "B.Cu" "B.Mask" "B.Paste")
			(net "PVDDIO_P1_VOS1")
		)
		(pad "2" smd circle
			(at -0.40005 0 90)
			(size 0 0)
			(layers "B.Cu" "B.Mask" "B.Paste")
			(net "PVDDIO_P1")
		)
	)
	(footprint ""
		(layer "B.Cu")
		(at 419.140894 -427.594014 180)
		(property "Reference" "R841"
			(at 0 0 0)
			(layer "B.SilkS")
			(hide yes)
			(effects
				(font
					(size 1.27 1.27)
				)
				(justify mirror)
			)
		)
		(property "Value" ""
			(at 0 0 0)
			(layer "B.Fab")
			(effects
				(font
					(size 1.27 1.27)
				)
				(justify mirror)
			)
		)
		(duplicate_pad_numbers_are_jumpers no)
		(fp_line
			(start 0.32512 0.175006)
			(end 0.32512 -0.175006)
			(stroke
				(width 0.1)
				(type default)
			)
			(layer "B.Fab")
		)
		(fp_line
			(start 0.32512 -0.175006)
			(end -0.32512 -0.175006)
			(stroke
				(width 0.1)
				(type default)
			)
			(layer "B.Fab")
		)
		(fp_line
			(start -0.32512 0.175006)
			(end 0.32512 0.175006)
			(stroke
				(width 0.1)
				(type default)
			)
			(layer "B.Fab")
		)
		(fp_line
			(start -0.32512 -0.175006)
			(end -0.32512 0.175006)
			(stroke
				(width 0.1)
				(type default)
			)
			(layer "B.Fab")
		)
		(pad "1" smd rect
			(at 0.2667 0)
			(size 0.3048 0.381)
			(layers "B.Cu" "B.Mask" "B.Paste")
			(net "P1V8_CPU0_RT_1D")
		)
		(pad "2" smd rect
			(at -0.2667 0 180)
			(size 0.3048 0.381)
			(layers "B.Cu" "B.Mask" "B.Paste")
			(net "SMB_RT_CPU0_P2_ROM_R_SCL")
		)
	)
)
